#ISCELL
  pure_quanta quanta_title_block_c *
  *
#CELL
  pure_quanta q_res *
  page321_i101
#ISCELL
  standard offpage *
  page321_i102
#ISCELL
  logical_power universal_gnd *
  page321_i70
#ISCELL
  standard offpage *
  page321_i71
#ISCELL
  standard offpage *
  page321_i72
#ISCELL
  standard offpage *
  page321_i73
#ISCELL
  logical_power universal_gnd *
  page321_i74
#ISCELL
  logical_power universal_power *
  page321_i75
#CELL
  pure_quanta q_res *
  page321_i77
#CELL
  pure_quanta q_res *
  page321_i78
#CELL
  pure_quanta q_res *
  page321_i79
#CELL
  pure_quanta q_res *
  page321_i80
#CELL
  pure_quanta q_cap *
  page321_i83
#CELL
  pure_quanta q_cap *
  page321_i85
#ISCELL
  logical_power universal_gnd *
  page321_i86
#ISCELL
  logical_power universal_power *
  page321_i87
#CELL
  pure_quanta gtl2014pw *
  page321_i91
#ISCELL
  logical_power universal_gnd *
  page321_i92
#ISCELL
  standard offpage *
  page321_i94
#ISCELL
  standard offpage *
  page321_i95
#ISCELL
  standard offpage *
  page321_i96
#CELL
  pure_quanta q_res *
  page321_i97
#CELL
  pure_quanta q_res *
  page321_i98
